# T6G (Grand Teton) — schematic netlist excerpt (pin names and nets, part order shuffled) for the footprints in the layout excerpt that follows; sources: Cadence DE-HDL packaged netlist, KiCad conversion of 04192023_DAF0TMB3IC0_F0TG_MB_C_brd_V02_OCP.brd

PC132  Q_CAP  100PF 50V 5% NPO  pkg 0402  page 192 : A = PVDD_33_S5_FB ; B = PVDD_33_S5
PR3919  Q_RES  0 5% CHIP  pkg 0402LF  page 263 : A = HSC_D_OC_1 ; B = HSC_D_OC_R

(kicad_pcb
	(version 20260206)
	(generator "pcbnew")
	(generator_version "10.0")
	(general
		(thickness 1.6)
		(legacy_teardrops no)
	)
	(paper "A4")
	(title_block
		(title "04192023_DAF0TMB3IC0_F0TG_MB_C_brd_V02_OCP.brd")
		(comment 1 "Grand Teton / footprints 2011-2012 of 8354")
	)
	(layers
		(0 "F.Cu" signal "TOP")
		(4 "In1.Cu" signal "GND")
		(6 "In2.Cu" signal "IN1")
		(8 "In3.Cu" signal "GND1")
		(10 "In4.Cu" signal "IN2")
		(12 "In5.Cu" signal "GND2")
		(14 "In6.Cu" signal "IN3")
		(16 "In7.Cu" signal "GND3")
		(18 "In8.Cu" signal "VCC")
		(20 "In9.Cu" signal "VCC1")
		(22 "In10.Cu" signal "GND4")
		(24 "In11.Cu" signal "IN4")
		(26 "In12.Cu" signal "GND5")
		(28 "In13.Cu" signal "IN5")
		(30 "In14.Cu" signal "GND6")
		(32 "In15.Cu" signal "IN6")
		(34 "In16.Cu" signal "GND7")
		(2 "B.Cu" signal "BOTTOM")
		(9 "F.Adhes" user "F.Adhesive")
		(11 "B.Adhes" user "B.Adhesive")
		(13 "F.Paste" user "Package Geometry/Pastemask Top")
		(15 "B.Paste" user "Package Geometry/Pastemask Bottom")
		(5 "F.SilkS" user "Ref Des/Silkscreen Top")
		(7 "B.SilkS" user "Ref Des/Silkscreen Bottom")
		(1 "F.Mask" user "Board Geometry/Soldermask Top")
		(3 "B.Mask" user "Board Geometry/Soldermask Bottom")
		(17 "Dwgs.User" user "User.Drawings")
		(19 "Cmts.User" user "User.Comments")
		(21 "Eco1.User" user "User.Eco1")
		(23 "Eco2.User" user "User.Eco2")
		(25 "Edge.Cuts" user "Board Geometry/Outline")
		(27 "Margin" user)
		(31 "F.CrtYd" user "Package Geometry/Place Bound Top")
		(29 "B.CrtYd" user "Package Geometry/Place Bound Bottom")
		(35 "F.Fab" user "Ref Des/Assembly Top")
		(33 "B.Fab" user "Ref Des/Assembly Bottom")
	)
	(footprint ""
		(layer "F.Cu")
		(at 206.381604 -342.075262 -90)
		(property "Reference" "PC132"
			(at 0 0 270)
			(layer "F.SilkS")
			(hide yes)
			(effects
				(font
					(size 1.27 1.27)
				)
			)
		)
		(property "Value" ""
			(at 0 0 270)
			(layer "F.Fab")
			(effects
				(font
					(size 1.27 1.27)
				)
			)
		)
		(duplicate_pad_numbers_are_jumpers no)
		(fp_line
			(start -0.7874 0.4064)
			(end -0.7874 -0.4064)
			(stroke
				(width 0.1524)
				(type default)
			)
			(layer "F.SilkS")
		)
		(fp_line
			(start 0.7874 0.4064)
			(end -0.7874 0.4064)
			(stroke
				(width 0.1524)
				(type default)
			)
			(layer "F.SilkS")
		)
		(fp_line
			(start -0.7874 -0.4064)
			(end 0.7874 -0.4064)
			(stroke
				(width 0.1524)
				(type default)
			)
			(layer "F.SilkS")
		)
		(fp_line
			(start 0.7874 -0.4064)
			(end 0.7874 0.4064)
			(stroke
				(width 0.1524)
				(type default)
			)
			(layer "F.SilkS")
		)
		(fp_line
			(start -0.67945 0.3048)
			(end -0.67945 -0.305054)
			(stroke
				(width 0.1)
				(type default)
			)
			(layer "F.Fab")
		)
		(fp_line
			(start -0.12065 0.3048)
			(end -0.67945 0.3048)
			(stroke
				(width 0.1)
				(type default)
			)
			(layer "F.Fab")
		)
		(fp_line
			(start 0.120396 0.3048)
			(end 0.120396 0.2794)
			(stroke
				(width 0.1)
				(type default)
			)
			(layer "F.Fab")
		)
		(fp_line
			(start 0.67945 0.3048)
			(end 0.120396 0.3048)
			(stroke
				(width 0.1)
				(type default)
			)
			(layer "F.Fab")
		)
		(fp_line
			(start -0.12065 0.2794)
			(end -0.12065 0.3048)
			(stroke
				(width 0.1)
				(type default)
			)
			(layer "F.Fab")
		)
		(fp_line
			(start 0.120396 0.2794)
			(end -0.12065 0.2794)
			(stroke
				(width 0.1)
				(type default)
			)
			(layer "F.Fab")
		)
		(fp_line
			(start -0.12065 -0.2794)
			(end 0.12065 -0.2794)
			(stroke
				(width 0.1)
				(type default)
			)
			(layer "F.Fab")
		)
		(fp_line
			(start 0.12065 -0.2794)
			(end 0.12065 -0.3048)
			(stroke
				(width 0.1)
				(type default)
			)
			(layer "F.Fab")
		)
		(fp_line
			(start 0.12065 -0.3048)
			(end 0.67945 -0.3048)
			(stroke
				(width 0.1)
				(type default)
			)
			(layer "F.Fab")
		)
		(fp_line
			(start 0.67945 -0.3048)
			(end 0.67945 0.3048)
			(stroke
				(width 0.1)
				(type default)
			)
			(layer "F.Fab")
		)
		(fp_line
			(start -0.67945 -0.305054)
			(end -0.12065 -0.305054)
			(stroke
				(width 0.1)
				(type default)
			)
			(layer "F.Fab")
		)
		(fp_line
			(start -0.12065 -0.305054)
			(end -0.12065 -0.2794)
			(stroke
				(width 0.1)
				(type default)
			)
			(layer "F.Fab")
		)
		(pad "1" smd circle
			(at -0.40005 0 270)
			(size 0 0)
			(layers "F.Cu" "F.Mask" "F.Paste")
			(net "PVDD_33_S5_FB")
		)
		(pad "2" smd circle
			(at 0.40005 0 270)
			(size 0 0)
			(layers "F.Cu" "F.Mask" "F.Paste")
			(net "PVDD_33_S5")
		)
	)
	(footprint ""
		(layer "F.Cu")
		(at 204.7621 -399.956782)
		(property "Reference" "PR3919"
			(at 0 0 0)
			(layer "F.SilkS")
			(hide yes)
			(effects
				(font
					(size 1.27 1.27)
				)
			)
		)
		(property "Value" ""
			(at 0 0 0)
			(layer "F.Fab")
			(effects
				(font
					(size 1.27 1.27)
				)
			)
		)
		(duplicate_pad_numbers_are_jumpers no)
		(fp_line
			(start -0.7874 -0.4064)
			(end 0.7874 -0.4064)
			(stroke
				(width 0.1524)
				(type default)
			)
			(layer "F.SilkS")
		)
		(fp_line
			(start -0.7874 0.4064)
			(end -0.7874 -0.4064)
			(stroke
				(width 0.1524)
				(type default)
			)
			(layer "F.SilkS")
		)
		(fp_line
			(start 0.7874 -0.4064)
			(end 0.7874 0.4064)
			(stroke
				(width 0.1524)
				(type default)
			)
			(layer "F.SilkS")
		)
		(fp_line
			(start 0.7874 0.4064)
			(end -0.7874 0.4064)
			(stroke
				(width 0.1524)
				(type default)
			)
			(layer "F.SilkS")
		)
		(fp_line
			(start -0.67945 -0.305054)
			(end -0.12065 -0.305054)
			(stroke
				(width 0.1)
				(type default)
			)
			(layer "F.Fab")
		)
		(fp_line
			(start -0.67945 0.3048)
			(end -0.67945 -0.305054)
			(stroke
				(width 0.1)
				(type default)
			)
			(layer "F.Fab")
		)
		(fp_line
			(start -0.12065 -0.305054)
			(end -0.12065 -0.2794)
			(stroke
				(width 0.1)
				(type default)
			)
			(layer "F.Fab")
		)
		(fp_line
			(start -0.12065 -0.2794)
			(end 0.12065 -0.2794)
			(stroke
				(width 0.1)
				(type default)
			)
			(layer "F.Fab")
		)
		(fp_line
			(start -0.12065 0.2794)
			(end -0.12065 0.3048)
			(stroke
				(width 0.1)
				(type default)
			)
			(layer "F.Fab")
		)
		(fp_line
			(start -0.12065 0.3048)
			(end -0.67945 0.3048)
			(stroke
				(width 0.1)
				(type default)
			)
			(layer "F.Fab")
		)
		(fp_line
			(start 0.120396 0.2794)
			(end -0.12065 0.2794)
			(stroke
				(width 0.1)
				(type default)
			)
			(layer "F.Fab")
		)
		(fp_line
			(start 0.120396 0.3048)
			(end 0.120396 0.2794)
			(stroke
				(width 0.1)
				(type default)
			)
			(layer "F.Fab")
		)
		(fp_line
			(start 0.12065 -0.3048)
			(end 0.67945 -0.3048)
			(stroke
				(width 0.1)
				(type default)
			)
			(layer "F.Fab")
		)
		(fp_line
			(start 0.12065 -0.2794)
			(end 0.12065 -0.3048)
			(stroke
				(width 0.1)
				(type default)
			)
			(layer "F.Fab")
		)
		(fp_line
			(start 0.67945 -0.3048)
			(end 0.67945 0.3048)
			(stroke
				(width 0.1)
				(type default)
			)
			(layer "F.Fab")
		)
		(fp_line
			(start 0.67945 0.3048)
			(end 0.120396 0.3048)
			(stroke
				(width 0.1)
				(type default)
			)
			(layer "F.Fab")
		)
		(pad "1" smd circle
			(at -0.40005 0)
			(size 0 0)
			(layers "F.Cu" "F.Mask" "F.Paste")
			(net "HSC_D_OC_1")
		)
		(pad "2" smd circle
			(at 0.40005 0)
			(size 0 0)
			(layers "F.Cu" "F.Mask" "F.Paste")
			(net "HSC_D_OC_R")
		)
	)
)
